(kicad_pcb
	(version 20260206)
	(generator "pcbnew")
	(generator_version "10.0")
	(general
		(thickness 1.6)
		(legacy_teardrops no)
	)
	(paper "A4")
	(title_block
		(title "01162023_DA0F0TEBIF0_F0T_Expander_BD_F_brd_V02_OCP.brd")
		(comment 1 "Grand Teton / footprints 1223-1229 of 9728")
	)
	(layers
		(0 "F.Cu" signal "TOP")
		(4 "In1.Cu" signal "GND")
		(6 "In2.Cu" signal "VCC")
		(8 "In3.Cu" signal "VCC1")
		(10 "In4.Cu" signal "GND1")
		(12 "In5.Cu" signal "IN1")
		(14 "In6.Cu" signal "GND2")
		(16 "In7.Cu" signal "IN2")
		(18 "In8.Cu" signal "GND3")
		(20 "In9.Cu" signal "IN3")
		(22 "In10.Cu" signal "GND4")
		(24 "In11.Cu" signal "IN4")
		(26 "In12.Cu" signal "GND5")
		(28 "In13.Cu" signal "IN5")
		(30 "In14.Cu" signal "GND6")
		(32 "In15.Cu" signal "IN6")
		(34 "In16.Cu" signal "GND7")
		(2 "B.Cu" signal "BOTTOM")
		(9 "F.Adhes" user "F.Adhesive")
		(11 "B.Adhes" user "B.Adhesive")
		(13 "F.Paste" user "Package Geometry/Pastemask Top")
		(15 "B.Paste" user "Package Geometry/Pastemask Bottom")
		(5 "F.SilkS" user "Ref Des/Silkscreen Top")
		(7 "B.SilkS" user "Ref Des/Silkscreen Bottom")
		(1 "F.Mask" user "Board Geometry/Soldermask Top")
		(3 "B.Mask" user "Board Geometry/Soldermask Bottom")
		(17 "Dwgs.User" user "User.Drawings")
		(19 "Cmts.User" user "User.Comments")
		(21 "Eco1.User" user "User.Eco1")
		(23 "Eco2.User" user "User.Eco2")
		(25 "Edge.Cuts" user "Board Geometry/Outline")
		(27 "Margin" user)
		(31 "F.CrtYd" user "Package Geometry/Place Bound Top")
		(29 "B.CrtYd" user "Package Geometry/Place Bound Bottom")
		(35 "F.Fab" user "Ref Des/Assembly Top")
		(33 "B.Fab" user "Ref Des/Assembly Bottom")
	)
	(footprint ""
		(layer "F.Cu")
		(at 63.6778 -116.550186 180)
		(property "Reference" "R58"
			(at 0 0 180)
			(layer "F.SilkS")
			(hide yes)
			(effects
				(font
					(size 1.27 1.27)
				)
			)
		)
		(property "Value" ""
			(at 0 0 180)
			(layer "F.Fab")
			(effects
				(font
					(size 1.27 1.27)
				)
			)
		)
		(duplicate_pad_numbers_are_jumpers no)
		(fp_line
			(start 0.7874 0.4064)
			(end -0.7874 0.4064)
			(stroke
				(width 0.1524)
				(type default)
			)
			(layer "F.SilkS")
		)
		(fp_line
			(start 0.7874 -0.4064)
			(end 0.7874 0.4064)
			(stroke
				(width 0.1524)
				(type default)
			)
			(layer "F.SilkS")
		)
		(fp_line
			(start -0.7874 0.4064)
			(end -0.7874 -0.4064)
			(stroke
				(width 0.1524)
				(type default)
			)
			(layer "F.SilkS")
		)
		(fp_line
			(start -0.7874 -0.4064)
			(end 0.7874 -0.4064)
			(stroke
				(width 0.1524)
				(type default)
			)
			(layer "F.SilkS")
		)
		(fp_line
			(start 0.67945 0.3048)
			(end 0.120396 0.3048)
			(stroke
				(width 0.1)
				(type default)
			)
			(layer "F.Fab")
		)
		(fp_line
			(start 0.67945 -0.3048)
			(end 0.67945 0.3048)
			(stroke
				(width 0.1)
				(type default)
			)
			(layer "F.Fab")
		)
		(fp_line
			(start 0.12065 -0.2794)
			(end 0.12065 -0.3048)
			(stroke
				(width 0.1)
				(type default)
			)
			(layer "F.Fab")
		)
		(fp_line
			(start 0.12065 -0.3048)
			(end 0.67945 -0.3048)
			(stroke
				(width 0.1)
				(type default)
			)
			(layer "F.Fab")
		)
		(fp_line
			(start 0.120396 0.3048)
			(end 0.120396 0.2794)
			(stroke
				(width 0.1)
				(type default)
			)
			(layer "F.Fab")
		)
		(fp_line
			(start 0.120396 0.2794)
			(end -0.12065 0.2794)
			(stroke
				(width 0.1)
				(type default)
			)
			(layer "F.Fab")
		)
		(fp_line
			(start -0.12065 0.3048)
			(end -0.67945 0.3048)
			(stroke
				(width 0.1)
				(type default)
			)
			(layer "F.Fab")
		)
		(fp_line
			(start -0.12065 0.2794)
			(end -0.12065 0.3048)
			(stroke
				(width 0.1)
				(type default)
			)
			(layer "F.Fab")
		)
		(fp_line
			(start -0.12065 -0.2794)
			(end 0.12065 -0.2794)
			(stroke
				(width 0.1)
				(type default)
			)
			(layer "F.Fab")
		)
		(fp_line
			(start -0.12065 -0.305054)
			(end -0.12065 -0.2794)
			(stroke
				(width 0.1)
				(type default)
			)
			(layer "F.Fab")
		)
		(fp_line
			(start -0.67945 0.3048)
			(end -0.67945 -0.305054)
			(stroke
				(width 0.1)
				(type default)
			)
			(layer "F.Fab")
		)
		(fp_line
			(start -0.67945 -0.305054)
			(end -0.12065 -0.305054)
			(stroke
				(width 0.1)
				(type default)
			)
			(layer "F.Fab")
		)
		(pad "1" smd circle
			(at -0.40005 0 180)
			(size 0 0)
			(layers "F.Cu" "F.Mask" "F.Paste")
			(net "PRSNTB2_NIC1_N")
		)
		(pad "2" smd circle
			(at 0.40005 0 180)
			(size 0 0)
			(layers "F.Cu" "F.Mask" "F.Paste")
			(net "P3V3_AUX")
		)
	)
	(footprint ""
		(layer "F.Cu")
		(at 105.951782 -108.054902 180)
		(property "Reference" "PC618"
			(at 0 0 180)
			(layer "F.SilkS")
			(hide yes)
			(effects
				(font
					(size 1.27 1.27)
				)
			)
		)
		(property "Value" ""
			(at 0 0 180)
			(layer "F.Fab")
			(effects
				(font
					(size 1.27 1.27)
				)
			)
		)
		(duplicate_pad_numbers_are_jumpers no)
		(fp_line
			(start 0.7874 0.4064)
			(end -0.7874 0.4064)
			(stroke
				(width 0.1524)
				(type default)
			)
			(layer "F.SilkS")
		)
		(fp_line
			(start 0.7874 -0.4064)
			(end 0.7874 0.4064)
			(stroke
				(width 0.1524)
				(type default)
			)
			(layer "F.SilkS")
		)
		(fp_line
			(start -0.7874 0.4064)
			(end -0.7874 -0.4064)
			(stroke
				(width 0.1524)
				(type default)
			)
			(layer "F.SilkS")
		)
		(fp_line
			(start -0.7874 -0.4064)
			(end 0.7874 -0.4064)
			(stroke
				(width 0.1524)
				(type default)
			)
			(layer "F.SilkS")
		)
		(fp_line
			(start 0.67945 0.3048)
			(end 0.120396 0.3048)
			(stroke
				(width 0.1)
				(type default)
			)
			(layer "F.Fab")
		)
		(fp_line
			(start 0.67945 -0.3048)
			(end 0.67945 0.3048)
			(stroke
				(width 0.1)
				(type default)
			)
			(layer "F.Fab")
		)
		(fp_line
			(start 0.12065 -0.2794)
			(end 0.12065 -0.3048)
			(stroke
				(width 0.1)
				(type default)
			)
			(layer "F.Fab")
		)
		(fp_line
			(start 0.12065 -0.3048)
			(end 0.67945 -0.3048)
			(stroke
				(width 0.1)
				(type default)
			)
			(layer "F.Fab")
		)
		(fp_line
			(start 0.120396 0.3048)
			(end 0.120396 0.2794)
			(stroke
				(width 0.1)
				(type default)
			)
			(layer "F.Fab")
		)
		(fp_line
			(start 0.120396 0.2794)
			(end -0.12065 0.2794)
			(stroke
				(width 0.1)
				(type default)
			)
			(layer "F.Fab")
		)
		(fp_line
			(start -0.12065 0.3048)
			(end -0.67945 0.3048)
			(stroke
				(width 0.1)
				(type default)
			)
			(layer "F.Fab")
		)
		(fp_line
			(start -0.12065 0.2794)
			(end -0.12065 0.3048)
			(stroke
				(width 0.1)
				(type default)
			)
			(layer "F.Fab")
		)
		(fp_line
			(start -0.12065 -0.2794)
			(end 0.12065 -0.2794)
			(stroke
				(width 0.1)
				(type default)
			)
			(layer "F.Fab")
		)
		(fp_line
			(start -0.12065 -0.305054)
			(end -0.12065 -0.2794)
			(stroke
				(width 0.1)
				(type default)
			)
			(layer "F.Fab")
		)
		(fp_line
			(start -0.67945 0.3048)
			(end -0.67945 -0.305054)
			(stroke
				(width 0.1)
				(type default)
			)
			(layer "F.Fab")
		)
		(fp_line
			(start -0.67945 -0.305054)
			(end -0.12065 -0.305054)
			(stroke
				(width 0.1)
				(type default)
			)
			(layer "F.Fab")
		)
		(pad "1" smd circle
			(at -0.40005 0 180)
			(size 0 0)
			(layers "F.Cu" "F.Mask" "F.Paste")
			(net "P12V_AUX")
		)
		(pad "2" smd circle
			(at 0.40005 0 180)
			(size 0 0)
			(layers "F.Cu" "F.Mask" "F.Paste")
			(net "GND")
		)
	)
	(footprint ""
		(layer "F.Cu")
		(at 196.119242 -118.670324 180)
		(property "Reference" "C243"
			(at 0 0 180)
			(layer "F.SilkS")
			(hide yes)
			(effects
				(font
					(size 1.27 1.27)
				)
			)
		)
		(property "Value" ""
			(at 0 0 180)
			(layer "F.Fab")
			(effects
				(font
					(size 1.27 1.27)
				)
			)
		)
		(duplicate_pad_numbers_are_jumpers no)
		(fp_line
			(start 0.299974 0.150114)
			(end -0.299974 0.150114)
			(stroke
				(width 0.1)
				(type default)
			)
			(layer "F.Fab")
		)
		(fp_line
			(start 0.299974 -0.150114)
			(end 0.299974 0.150114)
			(stroke
				(width 0.1)
				(type default)
			)
			(layer "F.Fab")
		)
		(fp_line
			(start -0.299974 0.150114)
			(end -0.299974 -0.150114)
			(stroke
				(width 0.1)
				(type default)
			)
			(layer "F.Fab")
		)
		(fp_line
			(start -0.299974 -0.150114)
			(end 0.299974 -0.150114)
			(stroke
				(width 0.1)
				(type default)
			)
			(layer "F.Fab")
		)
		(pad "1" smd rect
			(at -0.2667 0 180)
			(size 0.3048 0.381)
			(layers "F.Cu" "F.Mask" "F.Paste")
			(net "P5E_PEX1_STN0_TX_DN<0>")
		)
		(pad "2" smd rect
			(at 0.2667 0 180)
			(size 0.3048 0.381)
			(layers "F.Cu" "F.Mask" "F.Paste")
			(net "P5E_PEX1_STN0_TX_C_DN<0>")
		)
	)
	(footprint ""
		(layer "F.Cu")
		(at 62.709044 -212.5472 180)
		(property "Reference" "R6636"
			(at 0 0 180)
			(layer "F.SilkS")
			(hide yes)
			(effects
				(font
					(size 1.27 1.27)
				)
			)
		)
		(property "Value" ""
			(at 0 0 180)
			(layer "F.Fab")
			(effects
				(font
					(size 1.27 1.27)
				)
			)
		)
		(duplicate_pad_numbers_are_jumpers no)
		(fp_line
			(start 0.7874 0.4064)
			(end -0.7874 0.4064)
			(stroke
				(width 0.1524)
				(type default)
			)
			(layer "F.SilkS")
		)
		(fp_line
			(start 0.7874 -0.4064)
			(end 0.7874 0.4064)
			(stroke
				(width 0.1524)
				(type default)
			)
			(layer "F.SilkS")
		)
		(fp_line
			(start -0.7874 0.4064)
			(end -0.7874 -0.4064)
			(stroke
				(width 0.1524)
				(type default)
			)
			(layer "F.SilkS")
		)
		(fp_line
			(start -0.7874 -0.4064)
			(end 0.7874 -0.4064)
			(stroke
				(width 0.1524)
				(type default)
			)
			(layer "F.SilkS")
		)
		(fp_line
			(start 0.67945 0.3048)
			(end 0.120396 0.3048)
			(stroke
				(width 0.1)
				(type default)
			)
			(layer "F.Fab")
		)
		(fp_line
			(start 0.67945 -0.3048)
			(end 0.67945 0.3048)
			(stroke
				(width 0.1)
				(type default)
			)
			(layer "F.Fab")
		)
		(fp_line
			(start 0.12065 -0.2794)
			(end 0.12065 -0.3048)
			(stroke
				(width 0.1)
				(type default)
			)
			(layer "F.Fab")
		)
		(fp_line
			(start 0.12065 -0.3048)
			(end 0.67945 -0.3048)
			(stroke
				(width 0.1)
				(type default)
			)
			(layer "F.Fab")
		)
		(fp_line
			(start 0.120396 0.3048)
			(end 0.120396 0.2794)
			(stroke
				(width 0.1)
				(type default)
			)
			(layer "F.Fab")
		)
		(fp_line
			(start 0.120396 0.2794)
			(end -0.12065 0.2794)
			(stroke
				(width 0.1)
				(type default)
			)
			(layer "F.Fab")
		)
		(fp_line
			(start -0.12065 0.3048)
			(end -0.67945 0.3048)
			(stroke
				(width 0.1)
				(type default)
			)
			(layer "F.Fab")
		)
		(fp_line
			(start -0.12065 0.2794)
			(end -0.12065 0.3048)
			(stroke
				(width 0.1)
				(type default)
			)
			(layer "F.Fab")
		)
		(fp_line
			(start -0.12065 -0.2794)
			(end 0.12065 -0.2794)
			(stroke
				(width 0.1)
				(type default)
			)
			(layer "F.Fab")
		)
		(fp_line
			(start -0.12065 -0.305054)
			(end -0.12065 -0.2794)
			(stroke
				(width 0.1)
				(type default)
			)
			(layer "F.Fab")
		)
		(fp_line
			(start -0.67945 0.3048)
			(end -0.67945 -0.305054)
			(stroke
				(width 0.1)
				(type default)
			)
			(layer "F.Fab")
		)
		(fp_line
			(start -0.67945 -0.305054)
			(end -0.12065 -0.305054)
			(stroke
				(width 0.1)
				(type default)
			)
			(layer "F.Fab")
		)
		(pad "1" smd circle
			(at -0.40005 0 180)
			(size 0 0)
			(layers "F.Cu" "F.Mask" "F.Paste")
			(net "UART_PEX2_CLI_BUF_R_TX")
		)
		(pad "2" smd circle
			(at 0.40005 0 180)
			(size 0 0)
			(layers "F.Cu" "F.Mask" "F.Paste")
			(net "UART_PEX2_CLI_BUF_R1_TX")
		)
	)
	(footprint ""
		(layer "F.Cu")
		(at 404.28164 -158.8516)
		(property "Reference" "R353"
			(at 0 0 0)
			(layer "F.SilkS")
			(hide yes)
			(effects
				(font
					(size 1.27 1.27)
				)
			)
		)
		(property "Value" ""
			(at 0 0 0)
			(layer "F.Fab")
			(effects
				(font
					(size 1.27 1.27)
				)
			)
		)
		(duplicate_pad_numbers_are_jumpers no)
		(fp_line
			(start -0.7874 -0.4064)
			(end 0.7874 -0.4064)
			(stroke
				(width 0.1524)
				(type default)
			)
			(layer "F.SilkS")
		)
		(fp_line
			(start -0.7874 0.4064)
			(end -0.7874 -0.4064)
			(stroke
				(width 0.1524)
				(type default)
			)
			(layer "F.SilkS")
		)
		(fp_line
			(start 0.7874 -0.4064)
			(end 0.7874 0.4064)
			(stroke
				(width 0.1524)
				(type default)
			)
			(layer "F.SilkS")
		)
		(fp_line
			(start 0.7874 0.4064)
			(end -0.7874 0.4064)
			(stroke
				(width 0.1524)
				(type default)
			)
			(layer "F.SilkS")
		)
		(fp_line
			(start -0.67945 -0.305054)
			(end -0.12065 -0.305054)
			(stroke
				(width 0.1)
				(type default)
			)
			(layer "F.Fab")
		)
		(fp_line
			(start -0.67945 0.3048)
			(end -0.67945 -0.305054)
			(stroke
				(width 0.1)
				(type default)
			)
			(layer "F.Fab")
		)
		(fp_line
			(start -0.12065 -0.305054)
			(end -0.12065 -0.2794)
			(stroke
				(width 0.1)
				(type default)
			)
			(layer "F.Fab")
		)
		(fp_line
			(start -0.12065 -0.2794)
			(end 0.12065 -0.2794)
			(stroke
				(width 0.1)
				(type default)
			)
			(layer "F.Fab")
		)
		(fp_line
			(start -0.12065 0.2794)
			(end -0.12065 0.3048)
			(stroke
				(width 0.1)
				(type default)
			)
			(layer "F.Fab")
		)
		(fp_line
			(start -0.12065 0.3048)
			(end -0.67945 0.3048)
			(stroke
				(width 0.1)
				(type default)
			)
			(layer "F.Fab")
		)
		(fp_line
			(start 0.120396 0.2794)
			(end -0.12065 0.2794)
			(stroke
				(width 0.1)
				(type default)
			)
			(layer "F.Fab")
		)
		(fp_line
			(start 0.120396 0.3048)
			(end 0.120396 0.2794)
			(stroke
				(width 0.1)
				(type default)
			)
			(layer "F.Fab")
		)
		(fp_line
			(start 0.12065 -0.3048)
			(end 0.67945 -0.3048)
			(stroke
				(width 0.1)
				(type default)
			)
			(layer "F.Fab")
		)
		(fp_line
			(start 0.12065 -0.2794)
			(end 0.12065 -0.3048)
			(stroke
				(width 0.1)
				(type default)
			)
			(layer "F.Fab")
		)
		(fp_line
			(start 0.67945 -0.3048)
			(end 0.67945 0.3048)
			(stroke
				(width 0.1)
				(type default)
			)
			(layer "F.Fab")
		)
		(fp_line
			(start 0.67945 0.3048)
			(end 0.120396 0.3048)
			(stroke
				(width 0.1)
				(type default)
			)
			(layer "F.Fab")
		)
		(pad "1" smd circle
			(at -0.40005 0)
			(size 0 0)
			(layers "F.Cu" "F.Mask" "F.Paste")
			(net "RST_NIC6_PERST2_R_N")
		)
		(pad "2" smd circle
			(at 0.40005 0)
			(size 0 0)
			(layers "F.Cu" "F.Mask" "F.Paste")
			(net "RST_HP_NIC6_BUF_N")
		)
	)
	(footprint ""
		(layer "F.Cu")
		(at 85.53577 -289.230816 -90)
		(property "Reference" "R6388"
			(at 0 0 270)
			(layer "F.SilkS")
			(hide yes)
			(effects
				(font
					(size 1.27 1.27)
				)
			)
		)
		(property "Value" ""
			(at 0 0 270)
			(layer "F.Fab")
			(effects
				(font
					(size 1.27 1.27)
				)
			)
		)
		(duplicate_pad_numbers_are_jumpers no)
		(fp_line
			(start -0.7874 0.4064)
			(end -0.7874 -0.4064)
			(stroke
				(width 0.1524)
				(type default)
			)
			(layer "F.SilkS")
		)
		(fp_line
			(start 0.7874 0.4064)
			(end -0.7874 0.4064)
			(stroke
				(width 0.1524)
				(type default)
			)
			(layer "F.SilkS")
		)
		(fp_line
			(start -0.7874 -0.4064)
			(end 0.7874 -0.4064)
			(stroke
				(width 0.1524)
				(type default)
			)
			(layer "F.SilkS")
		)
		(fp_line
			(start 0.7874 -0.4064)
			(end 0.7874 0.4064)
			(stroke
				(width 0.1524)
				(type default)
			)
			(layer "F.SilkS")
		)
		(fp_line
			(start -0.67945 0.3048)
			(end -0.67945 -0.305054)
			(stroke
				(width 0.1)
				(type default)
			)
			(layer "F.Fab")
		)
		(fp_line
			(start -0.12065 0.3048)
			(end -0.67945 0.3048)
			(stroke
				(width 0.1)
				(type default)
			)
			(layer "F.Fab")
		)
		(fp_line
			(start 0.120396 0.3048)
			(end 0.120396 0.2794)
			(stroke
				(width 0.1)
				(type default)
			)
			(layer "F.Fab")
		)
		(fp_line
			(start 0.67945 0.3048)
			(end 0.120396 0.3048)
			(stroke
				(width 0.1)
				(type default)
			)
			(layer "F.Fab")
		)
		(fp_line
			(start -0.12065 0.2794)
			(end -0.12065 0.3048)
			(stroke
				(width 0.1)
				(type default)
			)
			(layer "F.Fab")
		)
		(fp_line
			(start 0.120396 0.2794)
			(end -0.12065 0.2794)
			(stroke
				(width 0.1)
				(type default)
			)
			(layer "F.Fab")
		)
		(fp_line
			(start -0.12065 -0.2794)
			(end 0.12065 -0.2794)
			(stroke
				(width 0.1)
				(type default)
			)
			(layer "F.Fab")
		)
		(fp_line
			(start 0.12065 -0.2794)
			(end 0.12065 -0.3048)
			(stroke
				(width 0.1)
				(type default)
			)
			(layer "F.Fab")
		)
		(fp_line
			(start 0.12065 -0.3048)
			(end 0.67945 -0.3048)
			(stroke
				(width 0.1)
				(type default)
			)
			(layer "F.Fab")
		)
		(fp_line
			(start 0.67945 -0.3048)
			(end 0.67945 0.3048)
			(stroke
				(width 0.1)
				(type default)
			)
			(layer "F.Fab")
		)
		(fp_line
			(start -0.67945 -0.305054)
			(end -0.12065 -0.305054)
			(stroke
				(width 0.1)
				(type default)
			)
			(layer "F.Fab")
		)
		(fp_line
			(start -0.12065 -0.305054)
			(end -0.12065 -0.2794)
			(stroke
				(width 0.1)
				(type default)
			)
			(layer "F.Fab")
		)
		(pad "1" smd circle
			(at -0.40005 0 270)
			(size 0 0)
			(layers "F.Cu" "F.Mask" "F.Paste")
			(net "RST_PEX0_S0_PERST_N")
		)
		(pad "2" smd circle
			(at 0.40005 0 270)
			(size 0 0)
			(layers "F.Cu" "F.Mask" "F.Paste")
			(net "RST_PEX0_S0_PERST_R_N")
		)
	)
	(footprint ""
		(layer "F.Cu")
		(at 83.866736 -52.543456 180)
		(property "Reference" "PC538"
			(at 0 0 180)
			(layer "F.SilkS")
			(hide yes)
			(effects
				(font
					(size 1.27 1.27)
				)
			)
		)
		(property "Value" ""
			(at 0 0 180)
			(layer "F.Fab")
			(effects
				(font
					(size 1.27 1.27)
				)
			)
		)
		(duplicate_pad_numbers_are_jumpers no)
		(fp_line
			(start 0.7874 0.4064)
			(end -0.7874 0.4064)
			(stroke
				(width 0.1524)
				(type default)
			)
			(layer "F.SilkS")
		)
		(fp_line
			(start 0.7874 -0.4064)
			(end 0.7874 0.4064)
			(stroke
				(width 0.1524)
				(type default)
			)
			(layer "F.SilkS")
		)
		(fp_line
			(start -0.7874 0.4064)
			(end -0.7874 -0.4064)
			(stroke
				(width 0.1524)
				(type default)
			)
			(layer "F.SilkS")
		)
		(fp_line
			(start -0.7874 -0.4064)
			(end 0.7874 -0.4064)
			(stroke
				(width 0.1524)
				(type default)
			)
			(layer "F.SilkS")
		)
		(fp_line
			(start 0.67945 0.3048)
			(end 0.120396 0.3048)
			(stroke
				(width 0.1)
				(type default)
			)
			(layer "F.Fab")
		)
		(fp_line
			(start 0.67945 -0.3048)
			(end 0.67945 0.3048)
			(stroke
				(width 0.1)
				(type default)
			)
			(layer "F.Fab")
		)
		(fp_line
			(start 0.12065 -0.2794)
			(end 0.12065 -0.3048)
			(stroke
				(width 0.1)
				(type default)
			)
			(layer "F.Fab")
		)
		(fp_line
			(start 0.12065 -0.3048)
			(end 0.67945 -0.3048)
			(stroke
				(width 0.1)
				(type default)
			)
			(layer "F.Fab")
		)
		(fp_line
			(start 0.120396 0.3048)
			(end 0.120396 0.2794)
			(stroke
				(width 0.1)
				(type default)
			)
			(layer "F.Fab")
		)
		(fp_line
			(start 0.120396 0.2794)
			(end -0.12065 0.2794)
			(stroke
				(width 0.1)
				(type default)
			)
			(layer "F.Fab")
		)
		(fp_line
			(start -0.12065 0.3048)
			(end -0.67945 0.3048)
			(stroke
				(width 0.1)
				(type default)
			)
			(layer "F.Fab")
		)
		(fp_line
			(start -0.12065 0.2794)
			(end -0.12065 0.3048)
			(stroke
				(width 0.1)
				(type default)
			)
			(layer "F.Fab")
		)
		(fp_line
			(start -0.12065 -0.2794)
			(end 0.12065 -0.2794)
			(stroke
				(width 0.1)
				(type default)
			)
			(layer "F.Fab")
		)
		(fp_line
			(start -0.12065 -0.305054)
			(end -0.12065 -0.2794)
			(stroke
				(width 0.1)
				(type default)
			)
			(layer "F.Fab")
		)
		(fp_line
			(start -0.67945 0.3048)
			(end -0.67945 -0.305054)
			(stroke
				(width 0.1)
				(type default)
			)
			(layer "F.Fab")
		)
		(fp_line
			(start -0.67945 -0.305054)
			(end -0.12065 -0.305054)
			(stroke
				(width 0.1)
				(type default)
			)
			(layer "F.Fab")
		)
		(pad "1" smd circle
			(at -0.40005 0 180)
			(size 0 0)
			(layers "F.Cu" "F.Mask" "F.Paste")
			(net "P3V3_SSD3")
		)
		(pad "2" smd circle
			(at 0.40005 0 180)
			(size 0 0)
			(layers "F.Cu" "F.Mask" "F.Paste")
			(net "GND")
		)
	)
)
